(kicad_pcb
	(version 20260206)
	(generator "pcbnew")
	(generator_version "10.0")
	(general
		(thickness 1.6)
		(legacy_teardrops no)
	)
	(paper "A4")
	(title_block
		(title "Wiwynn_Tioga_Pass_MB.brd")
		(comment 1 "Tioga Pass / footprints 2609-2615 of 4770")
	)
	(layers
		(0 "F.Cu" signal "TOP")
		(4 "In1.Cu" signal "L2GND")
		(6 "In2.Cu" signal "L3")
		(8 "In3.Cu" signal "L4GND")
		(10 "In4.Cu" signal "L5")
		(12 "In5.Cu" signal "L6GND")
		(14 "In6.Cu" signal "L7VCC")
		(16 "In7.Cu" signal "L8VCC")
		(18 "In8.Cu" signal "L9GND")
		(20 "In9.Cu" signal "L10")
		(22 "In10.Cu" signal "L11GND")
		(24 "In11.Cu" signal "L12")
		(26 "In12.Cu" signal "L13GND")
		(2 "B.Cu" signal "BOTTOM")
		(9 "F.Adhes" user "F.Adhesive")
		(11 "B.Adhes" user "B.Adhesive")
		(13 "F.Paste" user "Package Geometry/Pastemask Top")
		(15 "B.Paste" user "Package Geometry/Pastemask Bottom")
		(5 "F.SilkS" user "Ref Des/Silkscreen Top")
		(7 "B.SilkS" user "Ref Des/Silkscreen Bottom")
		(1 "F.Mask" user "Board Geometry/Soldermask Top")
		(3 "B.Mask" user "Board Geometry/Soldermask Bottom")
		(17 "Dwgs.User" user "User.Drawings")
		(19 "Cmts.User" user "User.Comments")
		(21 "Eco1.User" user "User.Eco1")
		(23 "Eco2.User" user "User.Eco2")
		(25 "Edge.Cuts" user "Board Geometry/Outline")
		(27 "Margin" user)
		(31 "F.CrtYd" user "Package Geometry/Place Bound Top")
		(29 "B.CrtYd" user "Package Geometry/Place Bound Bottom")
		(35 "F.Fab" user "Ref Des/Assembly Top")
		(33 "B.Fab" user "Ref Des/Assembly Bottom")
	)
	(footprint ""
		(layer "B.Cu")
		(at 390.93775 -108.65485 90)
		(property "Reference" "C2N9"
			(at 0 0 90)
			(layer "B.SilkS")
			(hide yes)
			(effects
				(font
					(size 1.27 1.27)
				)
				(justify mirror)
			)
		)
		(property "Value" ""
			(at 0 0 90)
			(layer "B.Fab")
			(effects
				(font
					(size 1.27 1.27)
				)
				(justify mirror)
			)
		)
		(duplicate_pad_numbers_are_jumpers no)
		(fp_rect
			(start 0.2794 0.9144)
			(end -0.2794 -0.1143)
			(stroke
				(width 0)
				(type default)
			)
			(fill no)
			(layer "B.CrtYd")
		)
		(fp_line
			(start 0.2794 -0.1143)
			(end -0.2794 -0.1143)
			(stroke
				(width 0.1)
				(type default)
			)
			(layer "B.Fab")
		)
		(fp_line
			(start -0.2794 -0.1143)
			(end -0.2794 0.9144)
			(stroke
				(width 0.1)
				(type default)
			)
			(layer "B.Fab")
		)
		(fp_line
			(start 0.2794 0.9144)
			(end 0.2794 -0.1143)
			(stroke
				(width 0.1)
				(type default)
			)
			(layer "B.Fab")
		)
		(fp_line
			(start -0.2794 0.9144)
			(end 0.2794 0.9144)
			(stroke
				(width 0.1)
				(type default)
			)
			(layer "B.Fab")
		)
		(pad "1" smd custom
			(at 0 0)
			(size 0.10414 0.10414)
			(layers "B.Cu" "B.Mask" "B.Paste")
			(net "PVNN_PCH_STBY")
			(options
				(clearance outline)
				(anchor circle)
			)
			(primitives
				(gr_poly
					(pts
						(xy -0.20828 -0.08636) (xy -0.20828 0.08636) (xy -0.08636 0.20828) (xy 0.086614 0.20828) (xy 0.20828 0.086614)
						(xy 0.20828 -0.08636) (xy 0.08636 -0.20828) (xy -0.08636 -0.20828)
					)
					(width 0)
					(fill yes)
				)
			)
		)
		(pad "2" smd custom
			(at 0 0.8001)
			(size 0.10414 0.10414)
			(layers "B.Cu" "B.Mask" "B.Paste")
			(net "GND")
			(options
				(clearance outline)
				(anchor circle)
			)
			(primitives
				(gr_poly
					(pts
						(xy -0.20828 -0.08636) (xy -0.20828 0.08636) (xy -0.08636 0.20828) (xy 0.086614 0.20828) (xy 0.20828 0.086614)
						(xy 0.20828 -0.08636) (xy 0.08636 -0.20828) (xy -0.08636 -0.20828)
					)
					(width 0)
					(fill yes)
				)
			)
		)
		(zone
			(layer "B.Cu")
			(hatch none 0.5)
			(connect_pads
				(clearance 0)
			)
			(min_thickness 0.25)
			(keepout
				(tracks allowed)
				(vias not_allowed)
				(pads allowed)
				(copperpour not_allowed)
				(footprints allowed)
			)
			(placement
				(enabled no)
				(sheetname "")
			)
			(fill
				(thermal_gap 0.5)
				(thermal_bridge_width 0.5)
				(island_removal_mode 0)
			)
			(polygon
				(pts
					(xy 391.1473 -108.74248) (xy 391.5283 -108.74248) (xy 391.5283 -108.56722) (xy 391.1473 -108.566966)
				)
			)
		)
		(zone
			(layer "B.Cu")
			(hatch none 0.5)
			(connect_pads
				(clearance 0)
			)
			(min_thickness 0.25)
			(keepout
				(tracks not_allowed)
				(vias allowed)
				(pads allowed)
				(copperpour not_allowed)
				(footprints allowed)
			)
			(placement
				(enabled no)
				(sheetname "")
			)
			(fill
				(thermal_gap 0.5)
				(thermal_bridge_width 0.5)
				(island_removal_mode 0)
			)
			(polygon
				(pts
					(xy 391.1473 -108.74248) (xy 391.5283 -108.74248) (xy 391.5283 -108.56722) (xy 391.1473 -108.566966)
				)
			)
		)
	)
	(footprint ""
		(layer "B.Cu")
		(at 24.257 -83.185 -90)
		(property "Reference" "R9P10"
			(at 0 0 90)
			(layer "B.SilkS")
			(hide yes)
			(effects
				(font
					(size 1.27 1.27)
				)
				(justify mirror)
			)
		)
		(property "Value" ""
			(at 0 0 90)
			(layer "B.Fab")
			(effects
				(font
					(size 1.27 1.27)
				)
				(justify mirror)
			)
		)
		(duplicate_pad_numbers_are_jumpers no)
		(fp_poly
			(pts
				(xy 0.2794 -0.1016) (xy -0.2794 -0.1016) (xy -0.2794 0.9906) (xy 0.2794 0.9906)
			)
			(stroke
				(width 0)
				(type default)
			)
			(fill no)
			(layer "B.CrtYd")
		)
		(fp_line
			(start -0.2794 0.9906)
			(end -0.2794 -0.1016)
			(stroke
				(width 0.1)
				(type default)
			)
			(layer "B.Fab")
		)
		(fp_line
			(start 0.2794 0.9906)
			(end -0.2794 0.9906)
			(stroke
				(width 0.1)
				(type default)
			)
			(layer "B.Fab")
		)
		(fp_line
			(start -0.2794 -0.1016)
			(end 0.2794 -0.1016)
			(stroke
				(width 0.1)
				(type default)
			)
			(layer "B.Fab")
		)
		(fp_line
			(start 0.2794 -0.1016)
			(end 0.2794 0.9906)
			(stroke
				(width 0.1)
				(type default)
			)
			(layer "B.Fab")
		)
		(pad "1" smd rect
			(at 0 0 90)
			(size 0.508 0.508)
			(layers "B.Cu" "B.Mask" "B.Paste")
			(net "P3V3_STBY")
		)
		(pad "2" smd rect
			(at 0 0.889 90)
			(size 0.508 0.508)
			(layers "B.Cu" "B.Mask" "B.Paste")
			(net "A_P12V_STBY_FPH_GATE")
		)
		(zone
			(layer "B.Cu")
			(hatch none 0.5)
			(connect_pads
				(clearance 0)
			)
			(min_thickness 0.25)
			(keepout
				(tracks not_allowed)
				(vias allowed)
				(pads allowed)
				(copperpour not_allowed)
				(footprints allowed)
			)
			(placement
				(enabled no)
				(sheetname "")
			)
			(fill
				(thermal_gap 0.5)
				(thermal_bridge_width 0.5)
				(island_removal_mode 0)
			)
			(polygon
				(pts
					(xy 23.622 -82.931) (xy 23.622 -83.439) (xy 24.003 -83.439) (xy 24.003 -82.931)
				)
			)
		)
		(zone
			(layer "B.Cu")
			(hatch none 0.5)
			(connect_pads
				(clearance 0)
			)
			(min_thickness 0.25)
			(keepout
				(tracks allowed)
				(vias not_allowed)
				(pads allowed)
				(copperpour not_allowed)
				(footprints allowed)
			)
			(placement
				(enabled no)
				(sheetname "")
			)
			(fill
				(thermal_gap 0.5)
				(thermal_bridge_width 0.5)
				(island_removal_mode 0)
			)
			(polygon
				(pts
					(xy 24.003 -82.931) (xy 24.003 -83.439) (xy 23.622 -83.439) (xy 23.622 -82.931)
				)
			)
		)
	)
	(footprint ""
		(layer "B.Cu")
		(at 32.832802 -81.030064 90)
		(property "Reference" "C9P24"
			(at 0 0 90)
			(layer "B.SilkS")
			(hide yes)
			(effects
				(font
					(size 1.27 1.27)
				)
				(justify mirror)
			)
		)
		(property "Value" ""
			(at 0 0 90)
			(layer "B.Fab")
			(effects
				(font
					(size 1.27 1.27)
				)
				(justify mirror)
			)
		)
		(duplicate_pad_numbers_are_jumpers no)
		(fp_poly
			(pts
				(xy 0.7239 -0.2159) (xy -0.7239 -0.2159) (xy -0.7239 1.9939) (xy 0.7239 1.9939)
			)
			(stroke
				(width 0)
				(type default)
			)
			(fill no)
			(layer "B.CrtYd")
		)
		(fp_line
			(start 0.7239 -0.2159)
			(end 0.7239 1.9939)
			(stroke
				(width 0.1)
				(type default)
			)
			(layer "B.Fab")
		)
		(fp_line
			(start -0.7239 -0.2159)
			(end 0.7239 -0.2159)
			(stroke
				(width 0.1)
				(type default)
			)
			(layer "B.Fab")
		)
		(fp_line
			(start 0.7239 1.9939)
			(end -0.7239 1.9939)
			(stroke
				(width 0.1)
				(type default)
			)
			(layer "B.Fab")
		)
		(fp_line
			(start -0.7239 1.9939)
			(end -0.7239 -0.2159)
			(stroke
				(width 0.1)
				(type default)
			)
			(layer "B.Fab")
		)
		(pad "1" smd rect
			(at 0 0 270)
			(size 1.27 1.016)
			(layers "B.Cu" "B.Mask" "B.Paste")
			(net "VR_FET_SW_P12V_STBY_PVCCIN_CPU1")
		)
		(pad "2" smd rect
			(at 0 1.778 270)
			(size 1.27 1.016)
			(layers "B.Cu" "B.Mask" "B.Paste")
			(net "GND")
		)
		(zone
			(layer "B.Cu")
			(hatch none 0.5)
			(connect_pads
				(clearance 0)
			)
			(min_thickness 0.25)
			(keepout
				(tracks not_allowed)
				(vias allowed)
				(pads allowed)
				(copperpour not_allowed)
				(footprints allowed)
			)
			(placement
				(enabled no)
				(sheetname "")
			)
			(fill
				(thermal_gap 0.5)
				(thermal_bridge_width 0.5)
				(island_removal_mode 0)
			)
			(polygon
				(pts
					(xy 33.340802 -81.665064) (xy 33.340802 -80.395064) (xy 34.102802 -80.395064) (xy 34.102802 -81.665064)
				)
			)
		)
	)
	(footprint ""
		(layer "B.Cu")
		(at 13.0048 -124.6505 180)
		(property "Reference" "R12W19"
			(at -1.01473 0.656336 270)
			(unlocked yes)
			(layer "B.SilkS")
			(effects
				(font
					(size 0.4064 0.254)
					(thickness 0.1524)
				)
				(justify mirror)
			)
		)
		(property "Value" ""
			(at 0 0 0)
			(layer "B.Fab")
			(effects
				(font
					(size 1.27 1.27)
				)
				(justify mirror)
			)
		)
		(duplicate_pad_numbers_are_jumpers no)
		(fp_poly
			(pts
				(xy 0.4953 -0.2032) (xy -0.4953 -0.2032) (xy -0.4953 1.6002) (xy 0.4953 1.6002)
			)
			(stroke
				(width 0)
				(type default)
			)
			(fill no)
			(layer "B.CrtYd")
		)
		(fp_line
			(start 0.4953 1.6002)
			(end 0.4953 -0.2032)
			(stroke
				(width 0.1)
				(type default)
			)
			(layer "B.Fab")
		)
		(fp_line
			(start 0.4953 -0.2032)
			(end -0.4953 -0.2032)
			(stroke
				(width 0.1)
				(type default)
			)
			(layer "B.Fab")
		)
		(fp_line
			(start -0.4953 1.6002)
			(end 0.4953 1.6002)
			(stroke
				(width 0.1)
				(type default)
			)
			(layer "B.Fab")
		)
		(fp_line
			(start -0.4953 -0.2032)
			(end -0.4953 1.6002)
			(stroke
				(width 0.1)
				(type default)
			)
			(layer "B.Fab")
		)
		(pad "1" smd rect
			(at 0 0)
			(size 0.762 0.889)
			(layers "B.Cu" "B.Mask" "B.Paste")
			(net "P12V_NVDIMM_KLM")
		)
		(pad "2" smd rect
			(at 0 1.397)
			(size 0.762 0.889)
			(layers "B.Cu" "B.Mask" "B.Paste")
			(net "PWRGD_PVDDQ_KLM_N")
		)
		(zone
			(layer "B.Cu")
			(hatch none 0.5)
			(connect_pads
				(clearance 0)
			)
			(min_thickness 0.25)
			(keepout
				(tracks not_allowed)
				(vias allowed)
				(pads allowed)
				(copperpour not_allowed)
				(footprints allowed)
			)
			(placement
				(enabled no)
				(sheetname "")
			)
			(fill
				(thermal_gap 0.5)
				(thermal_bridge_width 0.5)
				(island_removal_mode 0)
			)
			(polygon
				(pts
					(xy 12.6238 -125.603) (xy 12.6238 -125.095) (xy 13.3858 -125.095) (xy 13.3858 -125.603)
				)
			)
		)
		(zone
			(layer "B.Cu")
			(hatch none 0.5)
			(connect_pads
				(clearance 0)
			)
			(min_thickness 0.25)
			(keepout
				(tracks allowed)
				(vias not_allowed)
				(pads allowed)
				(copperpour not_allowed)
				(footprints allowed)
			)
			(placement
				(enabled no)
				(sheetname "")
			)
			(fill
				(thermal_gap 0.5)
				(thermal_bridge_width 0.5)
				(island_removal_mode 0)
			)
			(polygon
				(pts
					(xy 13.3858 -125.603) (xy 13.3858 -125.095) (xy 12.6238 -125.095) (xy 12.6238 -125.603)
				)
			)
		)
	)
	(footprint ""
		(layer "B.Cu")
		(at 465.7471 -41.23182)
		(property "Reference" "C9W17"
			(at -0.97536 0.76708 90)
			(unlocked yes)
			(layer "B.SilkS")
			(effects
				(font
					(size 0.4064 0.254)
					(thickness 0.1524)
				)
				(justify mirror)
			)
		)
		(property "Value" ""
			(at 0 0 0)
			(layer "B.Fab")
			(effects
				(font
					(size 1.27 1.27)
				)
				(justify mirror)
			)
		)
		(duplicate_pad_numbers_are_jumpers no)
		(fp_poly
			(pts
				(xy 0.4953 -0.2032) (xy -0.4953 -0.2032) (xy -0.4953 1.6002) (xy 0.4953 1.6002)
			)
			(stroke
				(width 0)
				(type default)
			)
			(fill no)
			(layer "B.CrtYd")
		)
		(fp_line
			(start -0.4953 -0.2032)
			(end -0.4953 1.6002)
			(stroke
				(width 0.1)
				(type default)
			)
			(layer "B.Fab")
		)
		(fp_line
			(start -0.4953 1.6002)
			(end 0.4953 1.6002)
			(stroke
				(width 0.1)
				(type default)
			)
			(layer "B.Fab")
		)
		(fp_line
			(start 0.4953 -0.2032)
			(end -0.4953 -0.2032)
			(stroke
				(width 0.1)
				(type default)
			)
			(layer "B.Fab")
		)
		(fp_line
			(start 0.4953 1.6002)
			(end 0.4953 -0.2032)
			(stroke
				(width 0.1)
				(type default)
			)
			(layer "B.Fab")
		)
		(pad "1" smd rect
			(at 0 0 180)
			(size 0.762 0.889)
			(layers "B.Cu" "B.Mask" "B.Paste")
			(net "P3V3_STBY")
		)
		(pad "2" smd rect
			(at 0 1.397 180)
			(size 0.762 0.889)
			(layers "B.Cu" "B.Mask" "B.Paste")
			(net "GND")
		)
		(zone
			(layer "B.Cu")
			(hatch none 0.5)
			(connect_pads
				(clearance 0)
			)
			(min_thickness 0.25)
			(keepout
				(tracks not_allowed)
				(vias allowed)
				(pads allowed)
				(copperpour not_allowed)
				(footprints allowed)
			)
			(placement
				(enabled no)
				(sheetname "")
			)
			(fill
				(thermal_gap 0.5)
				(thermal_bridge_width 0.5)
				(island_removal_mode 0)
			)
			(polygon
				(pts
					(xy 466.1281 -40.78732) (xy 465.3661 -40.78732) (xy 465.3661 -40.27932) (xy 466.1281 -40.27932)
				)
			)
		)
	)
	(footprint ""
		(layer "B.Cu")
		(at 333.346806 -60.368434)
		(property "Reference" "R2U14"
			(at 0 0 0)
			(layer "B.SilkS")
			(hide yes)
			(effects
				(font
					(size 1.27 1.27)
				)
				(justify mirror)
			)
		)
		(property "Value" ""
			(at 0 0 0)
			(layer "B.Fab")
			(effects
				(font
					(size 1.27 1.27)
				)
				(justify mirror)
			)
		)
		(duplicate_pad_numbers_are_jumpers no)
		(fp_poly
			(pts
				(xy 0.2794 -0.1016) (xy -0.2794 -0.1016) (xy -0.2794 0.9906) (xy 0.2794 0.9906)
			)
			(stroke
				(width 0)
				(type default)
			)
			(fill no)
			(layer "B.CrtYd")
		)
		(fp_line
			(start -0.2794 -0.1016)
			(end 0.2794 -0.1016)
			(stroke
				(width 0.1)
				(type default)
			)
			(layer "B.Fab")
		)
		(fp_line
			(start -0.2794 0.9906)
			(end -0.2794 -0.1016)
			(stroke
				(width 0.1)
				(type default)
			)
			(layer "B.Fab")
		)
		(fp_line
			(start 0.2794 -0.1016)
			(end 0.2794 0.9906)
			(stroke
				(width 0.1)
				(type default)
			)
			(layer "B.Fab")
		)
		(fp_line
			(start 0.2794 0.9906)
			(end -0.2794 0.9906)
			(stroke
				(width 0.1)
				(type default)
			)
			(layer "B.Fab")
		)
		(pad "1" smd rect
			(at 0 0 180)
			(size 0.508 0.508)
			(layers "B.Cu" "B.Mask" "B.Paste")
			(net "P3E_CPU0_PE1_SS_RXP<0>")
		)
		(pad "2" smd rect
			(at 0 0.889 180)
			(size 0.508 0.508)
			(layers "B.Cu" "B.Mask" "B.Paste")
			(net "P3E_CPU0_PE1_SS_R_RXP<0>")
		)
		(zone
			(layer "B.Cu")
			(hatch none 0.5)
			(connect_pads
				(clearance 0)
			)
			(min_thickness 0.25)
			(keepout
				(tracks allowed)
				(vias not_allowed)
				(pads allowed)
				(copperpour not_allowed)
				(footprints allowed)
			)
			(placement
				(enabled no)
				(sheetname "")
			)
			(fill
				(thermal_gap 0.5)
				(thermal_bridge_width 0.5)
				(island_removal_mode 0)
			)
			(polygon
				(pts
					(xy 333.600806 -60.114434) (xy 333.092806 -60.114434) (xy 333.092806 -59.733434) (xy 333.600806 -59.733434)
				)
			)
		)
		(zone
			(layer "B.Cu")
			(hatch none 0.5)
			(connect_pads
				(clearance 0)
			)
			(min_thickness 0.25)
			(keepout
				(tracks not_allowed)
				(vias allowed)
				(pads allowed)
				(copperpour not_allowed)
				(footprints allowed)
			)
			(placement
				(enabled no)
				(sheetname "")
			)
			(fill
				(thermal_gap 0.5)
				(thermal_bridge_width 0.5)
				(island_removal_mode 0)
			)
			(polygon
				(pts
					(xy 333.600806 -59.733434) (xy 333.092806 -59.733434) (xy 333.092806 -60.114434) (xy 333.600806 -60.114434)
				)
			)
		)
	)
	(footprint ""
		(layer "B.Cu")
		(at 469.646 -125.984 180)
		(property "Reference" "R1W12"
			(at 0.8382 -0.67818 180)
			(unlocked yes)
			(layer "B.SilkS")
			(effects
				(font
					(size 0.4064 0.254)
					(thickness 0.1524)
				)
				(justify left mirror)
			)
		)
		(property "Value" ""
			(at 0 0 0)
			(layer "B.Fab")
			(effects
				(font
					(size 1.27 1.27)
				)
				(justify mirror)
			)
		)
		(duplicate_pad_numbers_are_jumpers no)
		(fp_poly
			(pts
				(xy 0.2794 -0.1016) (xy -0.2794 -0.1016) (xy -0.2794 0.9906) (xy 0.2794 0.9906)
			)
			(stroke
				(width 0)
				(type default)
			)
			(fill no)
			(layer "B.CrtYd")
		)
		(fp_line
			(start 0.2794 0.9906)
			(end -0.2794 0.9906)
			(stroke
				(width 0.1)
				(type default)
			)
			(layer "B.Fab")
		)
		(fp_line
			(start 0.2794 -0.1016)
			(end 0.2794 0.9906)
			(stroke
				(width 0.1)
				(type default)
			)
			(layer "B.Fab")
		)
		(fp_line
			(start -0.2794 0.9906)
			(end -0.2794 -0.1016)
			(stroke
				(width 0.1)
				(type default)
			)
			(layer "B.Fab")
		)
		(fp_line
			(start -0.2794 -0.1016)
			(end 0.2794 -0.1016)
			(stroke
				(width 0.1)
				(type default)
			)
			(layer "B.Fab")
		)
		(pad "1" smd rect
			(at 0 0)
			(size 0.508 0.508)
			(layers "B.Cu" "B.Mask" "B.Paste")
			(net "FM_CPLD_USB_P0_EN_N")
		)
		(pad "2" smd rect
			(at 0 0.889)
			(size 0.508 0.508)
			(layers "B.Cu" "B.Mask" "B.Paste")
			(net "FM_USB_P0_EN_R_N")
		)
		(zone
			(layer "B.Cu")
			(hatch none 0.5)
			(connect_pads
				(clearance 0)
			)
			(min_thickness 0.25)
			(keepout
				(tracks not_allowed)
				(vias allowed)
				(pads allowed)
				(copperpour not_allowed)
				(footprints allowed)
			)
			(placement
				(enabled no)
				(sheetname "")
			)
			(fill
				(thermal_gap 0.5)
				(thermal_bridge_width 0.5)
				(island_removal_mode 0)
			)
			(polygon
				(pts
					(xy 469.392 -126.619) (xy 469.9 -126.619) (xy 469.9 -126.238) (xy 469.392 -126.238)
				)
			)
		)
		(zone
			(layer "B.Cu")
			(hatch none 0.5)
			(connect_pads
				(clearance 0)
			)
			(min_thickness 0.25)
			(keepout
				(tracks allowed)
				(vias not_allowed)
				(pads allowed)
				(copperpour not_allowed)
				(footprints allowed)
			)
			(placement
				(enabled no)
				(sheetname "")
			)
			(fill
				(thermal_gap 0.5)
				(thermal_bridge_width 0.5)
				(island_removal_mode 0)
			)
			(polygon
				(pts
					(xy 469.392 -126.238) (xy 469.9 -126.238) (xy 469.9 -126.619) (xy 469.392 -126.619)
				)
			)
		)
	)
)
